FILE_TYPE = CONNECTIVITY;
{Allegro Design Entry HDL 17.2-2016 S081 (4005846) 1/11/2022}
"PAGE_NUMBER" = 179;
0"NC";
1"GND\g";
2"PD_RCOMP_1P8_3P3";
3"TP_PCH_RSVD<13>"CDS_PHYS_NET_NAME"FM_PCH_SLP_S4_N";
4"TP_PCH_RSVD<12>"CDS_PHYS_NET_NAME"FM_PCH_SLP_S4_N";
5"TP_PCH_RSVD<7>";
6"TP_PCH_RSVD<6>";
7"TP_PCH_RSVD<2>";
8"TP_PCH_RSVD<1>";
9"TP_PCH_RSVD<0>";
%"Q_RES"
"2","(3475,2850)","0","pure_quanta","I2";
;
PART_NUMBER"CS12002FB06"
VALUE"200"
TOLERANCE"1%"
WATTAGE"1/16W"
MATERIAL"CHIP"
PACK_TYPE"0402LF"
$LOCATION"R497"
CDS_LIB"pure_quanta"
CDS_LOCATION"R497"
$SEC"1"
CDS_SEC"1";
"A"
$PN"1"2;
"B"
$PN"2"1;
%"UNIVERSAL_GND"
"1","(3475,2600)","0","logical_power","I3";
;
CDS_LIB"logical_power"
HDL_POWER"GND"
ROOM"IO_SLOT";
"A"1;
%"EMMITSBURG_REV0P9"
"9","(1350,3175)","0","pure_quanta","I4";
;
PART_NUMBER"AJ0QV2N0T00"
MATERIAL"IC"
VALUE"GFNOCPU04302300-QV2N-MM#99A1WT"
PART_TYPE"SMLF"
$LOCATION"U4"
NEEDS_NO_SIZE"TRUE"
CDS_LMAN_SYM_OUTLINE"-900,275,900,-275"
CDS_LIB"pure_quanta"
CDS_LOCATION"U4"
$SEC"9"
CDS_SEC"9";
"RSVD_H1"
$PN"H1"9;
"RSVD_F1"
$PN"F1"8;
"RSVD_A4"
$PN"A4"7;
"RSVD_P18"
$PN"P18"6;
"RSVD_BB43"
$PN"BB43"5;
"RSVD_N13"
$PN"N13"4;
"RSVD_L13"
$PN"L13"3;
"GPIO_RCOMP_1P8_3P3"
$PN"AC13"2;
END.
